# S9S_MB_2U (Grand Teton) — schematic netlist excerpt (pin names and nets, part order shuffled) for the footprints in the layout excerpt that follows; sources: Cadence DE-HDL packaged netlist, KiCad conversion of 03242023_DA0F0TMBIJ0_F0T_Motherboard_J_brd_V01_OCP.brd

R622  Q_RES  1K 1% CHIP  pkg 0402LF  page 199 : A = FM_PCH_SKIP_RTC_CLOCK ; B = GND
R3211  Q_RES  22 1% EMPTY  pkg 0402LF  page 160 : A = NCSI_BMC_RXD0_R1 ; B = RMII_OCP_BMC_RXD_0

(kicad_pcb
	(version 20260206)
	(generator "pcbnew")
	(generator_version "10.0")
	(general
		(thickness 1.6)
		(legacy_teardrops no)
	)
	(paper "A4")
	(title_block
		(title "03242023_DA0F0TMBIJ0_F0T_Motherboard_J_brd_V01_OCP.brd")
		(comment 1 "Grand Teton / footprints 5788-5789 of 6105")
	)
	(layers
		(0 "F.Cu" signal "TOP")
		(4 "In1.Cu" signal "GND")
		(6 "In2.Cu" signal "IN1")
		(8 "In3.Cu" signal "GND1")
		(10 "In4.Cu" signal "IN2")
		(12 "In5.Cu" signal "GND2")
		(14 "In6.Cu" signal "IN3")
		(16 "In7.Cu" signal "GND3")
		(18 "In8.Cu" signal "VCC")
		(20 "In9.Cu" signal "VCC1")
		(22 "In10.Cu" signal "GND4")
		(24 "In11.Cu" signal "IN4")
		(26 "In12.Cu" signal "GND5")
		(28 "In13.Cu" signal "IN5")
		(30 "In14.Cu" signal "GND6")
		(32 "In15.Cu" signal "IN6")
		(34 "In16.Cu" signal "GND7")
		(2 "B.Cu" signal "BOTTOM")
		(9 "F.Adhes" user "F.Adhesive")
		(11 "B.Adhes" user "B.Adhesive")
		(13 "F.Paste" user "Package Geometry/Pastemask Top")
		(15 "B.Paste" user "Package Geometry/Pastemask Bottom")
		(5 "F.SilkS" user "Ref Des/Silkscreen Top")
		(7 "B.SilkS" user "Ref Des/Silkscreen Bottom")
		(1 "F.Mask" user "Board Geometry/Soldermask Top")
		(3 "B.Mask" user "Board Geometry/Soldermask Bottom")
		(17 "Dwgs.User" user "User.Drawings")
		(19 "Cmts.User" user "User.Comments")
		(21 "Eco1.User" user "User.Eco1")
		(23 "Eco2.User" user "User.Eco2")
		(25 "Edge.Cuts" user "Board Geometry/Outline")
		(27 "Margin" user)
		(31 "F.CrtYd" user "Package Geometry/Place Bound Top")
		(29 "B.CrtYd" user "Package Geometry/Place Bound Bottom")
		(35 "F.Fab" user "Ref Des/Assembly Top")
		(33 "B.Fab" user "Ref Des/Assembly Bottom")
	)
	(footprint ""
		(layer "B.Cu")
		(at 216.212674 -76.591668 180)
		(property "Reference" "R3211"
			(at 0 0 0)
			(layer "B.SilkS")
			(hide yes)
			(effects
				(font
					(size 1.27 1.27)
				)
				(justify mirror)
			)
		)
		(property "Value" ""
			(at 0 0 0)
			(layer "B.Fab")
			(effects
				(font
					(size 1.27 1.27)
				)
				(justify mirror)
			)
		)
		(duplicate_pad_numbers_are_jumpers no)
		(fp_line
			(start 0.7874 0.4064)
			(end 0.7874 -0.4064)
			(stroke
				(width 0.1524)
				(type default)
			)
			(layer "B.SilkS")
		)
		(fp_line
			(start 0.7874 -0.4064)
			(end -0.7874 -0.4064)
			(stroke
				(width 0.1524)
				(type default)
			)
			(layer "B.SilkS")
		)
		(fp_line
			(start -0.7874 0.4064)
			(end 0.7874 0.4064)
			(stroke
				(width 0.1524)
				(type default)
			)
			(layer "B.SilkS")
		)
		(fp_line
			(start -0.7874 -0.4064)
			(end -0.7874 0.4064)
			(stroke
				(width 0.1524)
				(type default)
			)
			(layer "B.SilkS")
		)
		(fp_line
			(start 0.67945 0.3048)
			(end 0.67945 -0.305054)
			(stroke
				(width 0.1)
				(type default)
			)
			(layer "B.Fab")
		)
		(fp_line
			(start 0.67945 -0.305054)
			(end 0.12065 -0.305054)
			(stroke
				(width 0.1)
				(type default)
			)
			(layer "B.Fab")
		)
		(fp_line
			(start 0.12065 0.3048)
			(end 0.67945 0.3048)
			(stroke
				(width 0.1)
				(type default)
			)
			(layer "B.Fab")
		)
		(fp_line
			(start 0.12065 0.2794)
			(end 0.12065 0.3048)
			(stroke
				(width 0.1)
				(type default)
			)
			(layer "B.Fab")
		)
		(fp_line
			(start 0.12065 -0.2794)
			(end -0.12065 -0.2794)
			(stroke
				(width 0.1)
				(type default)
			)
			(layer "B.Fab")
		)
		(fp_line
			(start 0.12065 -0.305054)
			(end 0.12065 -0.2794)
			(stroke
				(width 0.1)
				(type default)
			)
			(layer "B.Fab")
		)
		(fp_line
			(start -0.120396 0.3048)
			(end -0.120396 0.2794)
			(stroke
				(width 0.1)
				(type default)
			)
			(layer "B.Fab")
		)
		(fp_line
			(start -0.120396 0.2794)
			(end 0.12065 0.2794)
			(stroke
				(width 0.1)
				(type default)
			)
			(layer "B.Fab")
		)
		(fp_line
			(start -0.12065 -0.2794)
			(end -0.12065 -0.3048)
			(stroke
				(width 0.1)
				(type default)
			)
			(layer "B.Fab")
		)
		(fp_line
			(start -0.12065 -0.3048)
			(end -0.67945 -0.3048)
			(stroke
				(width 0.1)
				(type default)
			)
			(layer "B.Fab")
		)
		(fp_line
			(start -0.67945 0.3048)
			(end -0.120396 0.3048)
			(stroke
				(width 0.1)
				(type default)
			)
			(layer "B.Fab")
		)
		(fp_line
			(start -0.67945 -0.3048)
			(end -0.67945 0.3048)
			(stroke
				(width 0.1)
				(type default)
			)
			(layer "B.Fab")
		)
		(pad "1" smd circle
			(at 0.40005 0)
			(size 0 0)
			(layers "B.Cu" "B.Mask" "B.Paste")
			(net "NCSI_BMC_RXD0_R1")
		)
		(pad "2" smd circle
			(at -0.40005 0)
			(size 0 0)
			(layers "B.Cu" "B.Mask" "B.Paste")
			(net "RMII_OCP_BMC_RXD_0")
		)
	)
	(footprint ""
		(layer "B.Cu")
		(at 320.645282 -26.71064 90)
		(property "Reference" "R622"
			(at 0 0 90)
			(layer "B.SilkS")
			(hide yes)
			(effects
				(font
					(size 1.27 1.27)
				)
				(justify mirror)
			)
		)
		(property "Value" ""
			(at 0 0 90)
			(layer "B.Fab")
			(effects
				(font
					(size 1.27 1.27)
				)
				(justify mirror)
			)
		)
		(duplicate_pad_numbers_are_jumpers no)
		(fp_line
			(start 0.7874 -0.4064)
			(end -0.7874 -0.4064)
			(stroke
				(width 0.1524)
				(type default)
			)
			(layer "B.SilkS")
		)
		(fp_line
			(start -0.7874 -0.4064)
			(end -0.7874 0.4064)
			(stroke
				(width 0.1524)
				(type default)
			)
			(layer "B.SilkS")
		)
		(fp_line
			(start 0.7874 0.4064)
			(end 0.7874 -0.4064)
			(stroke
				(width 0.1524)
				(type default)
			)
			(layer "B.SilkS")
		)
		(fp_line
			(start -0.7874 0.4064)
			(end 0.7874 0.4064)
			(stroke
				(width 0.1524)
				(type default)
			)
			(layer "B.SilkS")
		)
		(fp_line
			(start 0.67945 -0.305054)
			(end 0.12065 -0.305054)
			(stroke
				(width 0.1)
				(type default)
			)
			(layer "B.Fab")
		)
		(fp_line
			(start 0.12065 -0.305054)
			(end 0.12065 -0.2794)
			(stroke
				(width 0.1)
				(type default)
			)
			(layer "B.Fab")
		)
		(fp_line
			(start -0.12065 -0.3048)
			(end -0.67945 -0.3048)
			(stroke
				(width 0.1)
				(type default)
			)
			(layer "B.Fab")
		)
		(fp_line
			(start -0.67945 -0.3048)
			(end -0.67945 0.3048)
			(stroke
				(width 0.1)
				(type default)
			)
			(layer "B.Fab")
		)
		(fp_line
			(start 0.12065 -0.2794)
			(end -0.12065 -0.2794)
			(stroke
				(width 0.1)
				(type default)
			)
			(layer "B.Fab")
		)
		(fp_line
			(start -0.12065 -0.2794)
			(end -0.12065 -0.3048)
			(stroke
				(width 0.1)
				(type default)
			)
			(layer "B.Fab")
		)
		(fp_line
			(start 0.12065 0.2794)
			(end 0.12065 0.3048)
			(stroke
				(width 0.1)
				(type default)
			)
			(layer "B.Fab")
		)
		(fp_line
			(start -0.120396 0.2794)
			(end 0.12065 0.2794)
			(stroke
				(width 0.1)
				(type default)
			)
			(layer "B.Fab")
		)
		(fp_line
			(start 0.67945 0.3048)
			(end 0.67945 -0.305054)
			(stroke
				(width 0.1)
				(type default)
			)
			(layer "B.Fab")
		)
		(fp_line
			(start 0.12065 0.3048)
			(end 0.67945 0.3048)
			(stroke
				(width 0.1)
				(type default)
			)
			(layer "B.Fab")
		)
		(fp_line
			(start -0.120396 0.3048)
			(end -0.120396 0.2794)
			(stroke
				(width 0.1)
				(type default)
			)
			(layer "B.Fab")
		)
		(fp_line
			(start -0.67945 0.3048)
			(end -0.120396 0.3048)
			(stroke
				(width 0.1)
				(type default)
			)
			(layer "B.Fab")
		)
		(pad "1" smd circle
			(at 0.40005 0 270)
			(size 0 0)
			(layers "B.Cu" "B.Mask" "B.Paste")
			(net "FM_PCH_SKIP_RTC_CLOCK")
		)
		(pad "2" smd circle
			(at -0.40005 0 270)
			(size 0 0)
			(layers "B.Cu" "B.Mask" "B.Paste")
			(net "GND")
		)
	)
)
